# S9S_MB_2U (Grand Teton) — schematic netlist excerpt (pin names and nets, part order shuffled) for the footprints in the layout excerpt that follows; sources: Cadence DE-HDL packaged netlist, KiCad conversion of 03242023_DA0F0TMBIJ0_F0T_Motherboard_J_brd_V01_OCP.brd

PR4221  Q_RES  0 5% CHIP  pkg 0402LF  page 274 : A = NC_PVCCINFAON_CPU0_ACSP3 ; B = GND
R3451  Q_RES  4.7K 5% EMPTY  pkg 0402LF  page 149 : A = P3V3_AUX ; B = GPU_BASE_STBY_EN

(kicad_pcb
	(version 20260206)
	(generator "pcbnew")
	(generator_version "10.0")
	(general
		(thickness 1.6)
		(legacy_teardrops no)
	)
	(paper "A4")
	(title_block
		(title "03242023_DA0F0TMBIJ0_F0T_Motherboard_J_brd_V01_OCP.brd")
		(comment 1 "Grand Teton / footprints 2785-2786 of 6105")
	)
	(layers
		(0 "F.Cu" signal "TOP")
		(4 "In1.Cu" signal "GND")
		(6 "In2.Cu" signal "IN1")
		(8 "In3.Cu" signal "GND1")
		(10 "In4.Cu" signal "IN2")
		(12 "In5.Cu" signal "GND2")
		(14 "In6.Cu" signal "IN3")
		(16 "In7.Cu" signal "GND3")
		(18 "In8.Cu" signal "VCC")
		(20 "In9.Cu" signal "VCC1")
		(22 "In10.Cu" signal "GND4")
		(24 "In11.Cu" signal "IN4")
		(26 "In12.Cu" signal "GND5")
		(28 "In13.Cu" signal "IN5")
		(30 "In14.Cu" signal "GND6")
		(32 "In15.Cu" signal "IN6")
		(34 "In16.Cu" signal "GND7")
		(2 "B.Cu" signal "BOTTOM")
		(9 "F.Adhes" user "F.Adhesive")
		(11 "B.Adhes" user "B.Adhesive")
		(13 "F.Paste" user "Package Geometry/Pastemask Top")
		(15 "B.Paste" user "Package Geometry/Pastemask Bottom")
		(5 "F.SilkS" user "Ref Des/Silkscreen Top")
		(7 "B.SilkS" user "Ref Des/Silkscreen Bottom")
		(1 "F.Mask" user "Board Geometry/Soldermask Top")
		(3 "B.Mask" user "Board Geometry/Soldermask Bottom")
		(17 "Dwgs.User" user "User.Drawings")
		(19 "Cmts.User" user "User.Comments")
		(21 "Eco1.User" user "User.Eco1")
		(23 "Eco2.User" user "User.Eco2")
		(25 "Edge.Cuts" user "Board Geometry/Outline")
		(27 "Margin" user)
		(31 "F.CrtYd" user "Package Geometry/Place Bound Top")
		(29 "B.CrtYd" user "Package Geometry/Place Bound Bottom")
		(35 "F.Fab" user "Ref Des/Assembly Top")
		(33 "B.Fab" user "Ref Des/Assembly Bottom")
	)
	(footprint ""
		(layer "F.Cu")
		(at 426.73016 -143.675608 90)
		(property "Reference" "PR4221"
			(at 0 0 90)
			(layer "F.SilkS")
			(hide yes)
			(effects
				(font
					(size 1.27 1.27)
				)
			)
		)
		(property "Value" ""
			(at 0 0 90)
			(layer "F.Fab")
			(effects
				(font
					(size 1.27 1.27)
				)
			)
		)
		(duplicate_pad_numbers_are_jumpers no)
		(fp_line
			(start 0.7874 -0.4064)
			(end 0.7874 0.4064)
			(stroke
				(width 0.1524)
				(type default)
			)
			(layer "F.SilkS")
		)
		(fp_line
			(start -0.7874 -0.4064)
			(end 0.7874 -0.4064)
			(stroke
				(width 0.1524)
				(type default)
			)
			(layer "F.SilkS")
		)
		(fp_line
			(start 0.7874 0.4064)
			(end -0.7874 0.4064)
			(stroke
				(width 0.1524)
				(type default)
			)
			(layer "F.SilkS")
		)
		(fp_line
			(start -0.7874 0.4064)
			(end -0.7874 -0.4064)
			(stroke
				(width 0.1524)
				(type default)
			)
			(layer "F.SilkS")
		)
		(fp_line
			(start -0.12065 -0.305054)
			(end -0.12065 -0.2794)
			(stroke
				(width 0.1)
				(type default)
			)
			(layer "F.Fab")
		)
		(fp_line
			(start -0.67945 -0.305054)
			(end -0.12065 -0.305054)
			(stroke
				(width 0.1)
				(type default)
			)
			(layer "F.Fab")
		)
		(fp_line
			(start 0.67945 -0.3048)
			(end 0.67945 0.3048)
			(stroke
				(width 0.1)
				(type default)
			)
			(layer "F.Fab")
		)
		(fp_line
			(start 0.12065 -0.3048)
			(end 0.67945 -0.3048)
			(stroke
				(width 0.1)
				(type default)
			)
			(layer "F.Fab")
		)
		(fp_line
			(start 0.12065 -0.2794)
			(end 0.12065 -0.3048)
			(stroke
				(width 0.1)
				(type default)
			)
			(layer "F.Fab")
		)
		(fp_line
			(start -0.12065 -0.2794)
			(end 0.12065 -0.2794)
			(stroke
				(width 0.1)
				(type default)
			)
			(layer "F.Fab")
		)
		(fp_line
			(start 0.120396 0.2794)
			(end -0.12065 0.2794)
			(stroke
				(width 0.1)
				(type default)
			)
			(layer "F.Fab")
		)
		(fp_line
			(start -0.12065 0.2794)
			(end -0.12065 0.3048)
			(stroke
				(width 0.1)
				(type default)
			)
			(layer "F.Fab")
		)
		(fp_line
			(start 0.67945 0.3048)
			(end 0.120396 0.3048)
			(stroke
				(width 0.1)
				(type default)
			)
			(layer "F.Fab")
		)
		(fp_line
			(start 0.120396 0.3048)
			(end 0.120396 0.2794)
			(stroke
				(width 0.1)
				(type default)
			)
			(layer "F.Fab")
		)
		(fp_line
			(start -0.12065 0.3048)
			(end -0.67945 0.3048)
			(stroke
				(width 0.1)
				(type default)
			)
			(layer "F.Fab")
		)
		(fp_line
			(start -0.67945 0.3048)
			(end -0.67945 -0.305054)
			(stroke
				(width 0.1)
				(type default)
			)
			(layer "F.Fab")
		)
		(pad "1" smd circle
			(at -0.40005 0 90)
			(size 0 0)
			(layers "F.Cu" "F.Mask" "F.Paste")
			(net "NC_PVCCINFAON_CPU0_ACSP3")
		)
		(pad "2" smd circle
			(at 0.40005 0 90)
			(size 0 0)
			(layers "F.Cu" "F.Mask" "F.Paste")
			(net "GND")
		)
	)
	(footprint ""
		(layer "F.Cu")
		(at 163.50488 -436.463948)
		(property "Reference" "R3451"
			(at 0 0 0)
			(layer "F.SilkS")
			(hide yes)
			(effects
				(font
					(size 1.27 1.27)
				)
			)
		)
		(property "Value" ""
			(at 0 0 0)
			(layer "F.Fab")
			(effects
				(font
					(size 1.27 1.27)
				)
			)
		)
		(duplicate_pad_numbers_are_jumpers no)
		(fp_line
			(start -0.7874 -0.4064)
			(end 0.7874 -0.4064)
			(stroke
				(width 0.1524)
				(type default)
			)
			(layer "F.SilkS")
		)
		(fp_line
			(start -0.7874 0.4064)
			(end -0.7874 -0.4064)
			(stroke
				(width 0.1524)
				(type default)
			)
			(layer "F.SilkS")
		)
		(fp_line
			(start 0.7874 -0.4064)
			(end 0.7874 0.4064)
			(stroke
				(width 0.1524)
				(type default)
			)
			(layer "F.SilkS")
		)
		(fp_line
			(start 0.7874 0.4064)
			(end -0.7874 0.4064)
			(stroke
				(width 0.1524)
				(type default)
			)
			(layer "F.SilkS")
		)
		(fp_line
			(start -0.67945 -0.305054)
			(end -0.12065 -0.305054)
			(stroke
				(width 0.1)
				(type default)
			)
			(layer "F.Fab")
		)
		(fp_line
			(start -0.67945 0.3048)
			(end -0.67945 -0.305054)
			(stroke
				(width 0.1)
				(type default)
			)
			(layer "F.Fab")
		)
		(fp_line
			(start -0.12065 -0.305054)
			(end -0.12065 -0.2794)
			(stroke
				(width 0.1)
				(type default)
			)
			(layer "F.Fab")
		)
		(fp_line
			(start -0.12065 -0.2794)
			(end 0.12065 -0.2794)
			(stroke
				(width 0.1)
				(type default)
			)
			(layer "F.Fab")
		)
		(fp_line
			(start -0.12065 0.2794)
			(end -0.12065 0.3048)
			(stroke
				(width 0.1)
				(type default)
			)
			(layer "F.Fab")
		)
		(fp_line
			(start -0.12065 0.3048)
			(end -0.67945 0.3048)
			(stroke
				(width 0.1)
				(type default)
			)
			(layer "F.Fab")
		)
		(fp_line
			(start 0.120396 0.2794)
			(end -0.12065 0.2794)
			(stroke
				(width 0.1)
				(type default)
			)
			(layer "F.Fab")
		)
		(fp_line
			(start 0.120396 0.3048)
			(end 0.120396 0.2794)
			(stroke
				(width 0.1)
				(type default)
			)
			(layer "F.Fab")
		)
		(fp_line
			(start 0.12065 -0.3048)
			(end 0.67945 -0.3048)
			(stroke
				(width 0.1)
				(type default)
			)
			(layer "F.Fab")
		)
		(fp_line
			(start 0.12065 -0.2794)
			(end 0.12065 -0.3048)
			(stroke
				(width 0.1)
				(type default)
			)
			(layer "F.Fab")
		)
		(fp_line
			(start 0.67945 -0.3048)
			(end 0.67945 0.3048)
			(stroke
				(width 0.1)
				(type default)
			)
			(layer "F.Fab")
		)
		(fp_line
			(start 0.67945 0.3048)
			(end 0.120396 0.3048)
			(stroke
				(width 0.1)
				(type default)
			)
			(layer "F.Fab")
		)
		(pad "1" smd circle
			(at -0.40005 0)
			(size 0 0)
			(layers "F.Cu" "F.Mask" "F.Paste")
			(net "P3V3_AUX")
		)
		(pad "2" smd circle
			(at 0.40005 0)
			(size 0 0)
			(layers "F.Cu" "F.Mask" "F.Paste")
			(net "GPU_BASE_STBY_EN")
		)
	)
)
